# SCM (Grand Teton) — schematic netlist excerpt (pin names and nets, part order shuffled) for the footprints in the layout excerpt that follows; sources: Cadence DE-HDL packaged netlist, KiCad conversion of 12092022_DA0F0TMDCD0_F0T_Management_Board_D_brd_V3_OCP.brd

R10  Q_RES  0 5% CHIP  pkg 0402LF  page 34 : A = RST_SRST_PLD_BMC_R2_N ; B = RST_SRST_PLD_BMC_R_N
R743  Q_RES  100 1% EMPTY  pkg 0402LF  page 28 : A = LED_POSTCODE_A0 ; B = GND

(kicad_pcb
	(version 20260206)
	(generator "pcbnew")
	(generator_version "10.0")
	(general
		(thickness 1.6)
		(legacy_teardrops no)
	)
	(paper "A4")
	(title_block
		(title "12092022_DA0F0TMDCD0_F0T_Management_Board_D_brd_V3_OCP.brd")
		(comment 1 "Grand Teton / footprints 1411-1412 of 1440")
	)
	(layers
		(0 "F.Cu" signal "TOP")
		(4 "In1.Cu" signal "GND")
		(6 "In2.Cu" signal "IN1")
		(8 "In3.Cu" signal "GND1")
		(10 "In4.Cu" signal "IN2")
		(12 "In5.Cu" signal "VCC")
		(14 "In6.Cu" signal "VCC1")
		(16 "In7.Cu" signal "IN3")
		(18 "In8.Cu" signal "GND2")
		(20 "In9.Cu" signal "IN4")
		(22 "In10.Cu" signal "GND3")
		(2 "B.Cu" signal "BOTTOM")
		(9 "F.Adhes" user "F.Adhesive")
		(11 "B.Adhes" user "B.Adhesive")
		(13 "F.Paste" user "Package Geometry/Pastemask Top")
		(15 "B.Paste" user "Package Geometry/Pastemask Bottom")
		(5 "F.SilkS" user "Ref Des/Silkscreen Top")
		(7 "B.SilkS" user "Ref Des/Silkscreen Bottom")
		(1 "F.Mask" user "Board Geometry/Soldermask Top")
		(3 "B.Mask" user "Board Geometry/Soldermask Bottom")
		(17 "Dwgs.User" user "User.Drawings")
		(19 "Cmts.User" user "User.Comments")
		(21 "Eco1.User" user "User.Eco1")
		(23 "Eco2.User" user "User.Eco2")
		(25 "Edge.Cuts" user "Board Geometry/Outline")
		(27 "Margin" user)
		(31 "F.CrtYd" user "Package Geometry/Place Bound Top")
		(29 "B.CrtYd" user "Package Geometry/Place Bound Bottom")
		(35 "F.Fab" user "Ref Des/Assembly Top")
		(33 "B.Fab" user "Ref Des/Assembly Bottom")
	)
	(footprint ""
		(layer "B.Cu")
		(at 59.7916 -95.0214 180)
		(property "Reference" "R743"
			(at 0 0 0)
			(layer "B.SilkS")
			(hide yes)
			(effects
				(font
					(size 1.27 1.27)
				)
				(justify mirror)
			)
		)
		(property "Value" ""
			(at 0 0 0)
			(layer "B.Fab")
			(effects
				(font
					(size 1.27 1.27)
				)
				(justify mirror)
			)
		)
		(duplicate_pad_numbers_are_jumpers no)
		(fp_line
			(start 0.7874 0.4064)
			(end 0.7874 -0.4064)
			(stroke
				(width 0.1524)
				(type default)
			)
			(layer "B.SilkS")
		)
		(fp_line
			(start 0.7874 -0.4064)
			(end -0.7874 -0.4064)
			(stroke
				(width 0.1524)
				(type default)
			)
			(layer "B.SilkS")
		)
		(fp_line
			(start -0.7874 0.4064)
			(end 0.7874 0.4064)
			(stroke
				(width 0.1524)
				(type default)
			)
			(layer "B.SilkS")
		)
		(fp_line
			(start -0.7874 -0.4064)
			(end -0.7874 0.4064)
			(stroke
				(width 0.1524)
				(type default)
			)
			(layer "B.SilkS")
		)
		(fp_line
			(start 0.67945 0.3048)
			(end 0.67945 -0.305054)
			(stroke
				(width 0.1)
				(type default)
			)
			(layer "B.Fab")
		)
		(fp_line
			(start 0.67945 -0.305054)
			(end 0.12065 -0.305054)
			(stroke
				(width 0.1)
				(type default)
			)
			(layer "B.Fab")
		)
		(fp_line
			(start 0.12065 0.3048)
			(end 0.67945 0.3048)
			(stroke
				(width 0.1)
				(type default)
			)
			(layer "B.Fab")
		)
		(fp_line
			(start 0.12065 0.2794)
			(end 0.12065 0.3048)
			(stroke
				(width 0.1)
				(type default)
			)
			(layer "B.Fab")
		)
		(fp_line
			(start 0.12065 -0.2794)
			(end -0.12065 -0.2794)
			(stroke
				(width 0.1)
				(type default)
			)
			(layer "B.Fab")
		)
		(fp_line
			(start 0.12065 -0.305054)
			(end 0.12065 -0.2794)
			(stroke
				(width 0.1)
				(type default)
			)
			(layer "B.Fab")
		)
		(fp_line
			(start -0.120396 0.3048)
			(end -0.120396 0.2794)
			(stroke
				(width 0.1)
				(type default)
			)
			(layer "B.Fab")
		)
		(fp_line
			(start -0.120396 0.2794)
			(end 0.12065 0.2794)
			(stroke
				(width 0.1)
				(type default)
			)
			(layer "B.Fab")
		)
		(fp_line
			(start -0.12065 -0.2794)
			(end -0.12065 -0.3048)
			(stroke
				(width 0.1)
				(type default)
			)
			(layer "B.Fab")
		)
		(fp_line
			(start -0.12065 -0.3048)
			(end -0.67945 -0.3048)
			(stroke
				(width 0.1)
				(type default)
			)
			(layer "B.Fab")
		)
		(fp_line
			(start -0.67945 0.3048)
			(end -0.120396 0.3048)
			(stroke
				(width 0.1)
				(type default)
			)
			(layer "B.Fab")
		)
		(fp_line
			(start -0.67945 -0.3048)
			(end -0.67945 0.3048)
			(stroke
				(width 0.1)
				(type default)
			)
			(layer "B.Fab")
		)
		(pad "1" smd circle
			(at 0.40005 0)
			(size 0 0)
			(layers "B.Cu" "B.Mask" "B.Paste")
			(net "LED_POSTCODE_A0")
		)
		(pad "2" smd circle
			(at -0.40005 0)
			(size 0 0)
			(layers "B.Cu" "B.Mask" "B.Paste")
			(net "GND")
		)
	)
	(footprint ""
		(layer "B.Cu")
		(at 5.334 -81.534 -90)
		(property "Reference" "R10"
			(at 0 0 90)
			(layer "B.SilkS")
			(hide yes)
			(effects
				(font
					(size 1.27 1.27)
				)
				(justify mirror)
			)
		)
		(property "Value" ""
			(at 0 0 90)
			(layer "B.Fab")
			(effects
				(font
					(size 1.27 1.27)
				)
				(justify mirror)
			)
		)
		(duplicate_pad_numbers_are_jumpers no)
		(fp_line
			(start -0.7874 0.4064)
			(end 0.7874 0.4064)
			(stroke
				(width 0.1524)
				(type default)
			)
			(layer "B.SilkS")
		)
		(fp_line
			(start 0.7874 0.4064)
			(end 0.7874 -0.4064)
			(stroke
				(width 0.1524)
				(type default)
			)
			(layer "B.SilkS")
		)
		(fp_line
			(start -0.7874 -0.4064)
			(end -0.7874 0.4064)
			(stroke
				(width 0.1524)
				(type default)
			)
			(layer "B.SilkS")
		)
		(fp_line
			(start 0.7874 -0.4064)
			(end -0.7874 -0.4064)
			(stroke
				(width 0.1524)
				(type default)
			)
			(layer "B.SilkS")
		)
		(fp_line
			(start -0.67945 0.3048)
			(end -0.120396 0.3048)
			(stroke
				(width 0.1)
				(type default)
			)
			(layer "B.Fab")
		)
		(fp_line
			(start -0.120396 0.3048)
			(end -0.120396 0.2794)
			(stroke
				(width 0.1)
				(type default)
			)
			(layer "B.Fab")
		)
		(fp_line
			(start 0.12065 0.3048)
			(end 0.67945 0.3048)
			(stroke
				(width 0.1)
				(type default)
			)
			(layer "B.Fab")
		)
		(fp_line
			(start 0.67945 0.3048)
			(end 0.67945 -0.305054)
			(stroke
				(width 0.1)
				(type default)
			)
			(layer "B.Fab")
		)
		(fp_line
			(start -0.120396 0.2794)
			(end 0.12065 0.2794)
			(stroke
				(width 0.1)
				(type default)
			)
			(layer "B.Fab")
		)
		(fp_line
			(start 0.12065 0.2794)
			(end 0.12065 0.3048)
			(stroke
				(width 0.1)
				(type default)
			)
			(layer "B.Fab")
		)
		(fp_line
			(start -0.12065 -0.2794)
			(end -0.12065 -0.3048)
			(stroke
				(width 0.1)
				(type default)
			)
			(layer "B.Fab")
		)
		(fp_line
			(start 0.12065 -0.2794)
			(end -0.12065 -0.2794)
			(stroke
				(width 0.1)
				(type default)
			)
			(layer "B.Fab")
		)
		(fp_line
			(start -0.67945 -0.3048)
			(end -0.67945 0.3048)
			(stroke
				(width 0.1)
				(type default)
			)
			(layer "B.Fab")
		)
		(fp_line
			(start -0.12065 -0.3048)
			(end -0.67945 -0.3048)
			(stroke
				(width 0.1)
				(type default)
			)
			(layer "B.Fab")
		)
		(fp_line
			(start 0.12065 -0.305054)
			(end 0.12065 -0.2794)
			(stroke
				(width 0.1)
				(type default)
			)
			(layer "B.Fab")
		)
		(fp_line
			(start 0.67945 -0.305054)
			(end 0.12065 -0.305054)
			(stroke
				(width 0.1)
				(type default)
			)
			(layer "B.Fab")
		)
		(pad "1" smd circle
			(at 0.40005 0 90)
			(size 0 0)
			(layers "B.Cu" "B.Mask" "B.Paste")
			(net "RST_SRST_PLD_BMC_R2_N")
		)
		(pad "2" smd circle
			(at -0.40005 0 90)
			(size 0 0)
			(layers "B.Cu" "B.Mask" "B.Paste")
			(net "RST_SRST_PLD_BMC_R_N")
		)
	)
)
